# BASEBOARD_FAB2 (Tioga Pass) — schematic netlist excerpt (pin names and nets, part order shuffled) for the footprints in the layout excerpt that follows; sources: Cadence DE-HDL packaged netlist, KiCad conversion of Wiwynn_Tioga_Pass_MB.brd

R8D27  RES  1.00K 1% CHIP  pkg 0402  page 167 : A = PD_FRU_WP ; B = GND
R1B11  RES  0.0 5% CHIP  pkg 0402  page 226 : A = SVID_ALERT_PVDDQ_KLM ; B = SVID_ALERT1_CPU1_R_N
C8E7  SC22U16V5MX-4-GP  20%  pkg SMD-BCG5  page 241 : \1\ = P5V_STBY ; \2\ = GND

(kicad_pcb
	(version 20260206)
	(generator "pcbnew")
	(generator_version "10.0")
	(general
		(thickness 1.6)
		(legacy_teardrops no)
	)
	(paper "A4")
	(title_block
		(title "Wiwynn_Tioga_Pass_MB.brd")
		(comment 1 "Tioga Pass / footprints 95-97 of 4770")
	)
	(layers
		(0 "F.Cu" signal "TOP")
		(4 "In1.Cu" signal "L2GND")
		(6 "In2.Cu" signal "L3")
		(8 "In3.Cu" signal "L4GND")
		(10 "In4.Cu" signal "L5")
		(12 "In5.Cu" signal "L6GND")
		(14 "In6.Cu" signal "L7VCC")
		(16 "In7.Cu" signal "L8VCC")
		(18 "In8.Cu" signal "L9GND")
		(20 "In9.Cu" signal "L10")
		(22 "In10.Cu" signal "L11GND")
		(24 "In11.Cu" signal "L12")
		(26 "In12.Cu" signal "L13GND")
		(2 "B.Cu" signal "BOTTOM")
		(9 "F.Adhes" user "F.Adhesive")
		(11 "B.Adhes" user "B.Adhesive")
		(13 "F.Paste" user "Package Geometry/Pastemask Top")
		(15 "B.Paste" user "Package Geometry/Pastemask Bottom")
		(5 "F.SilkS" user "Ref Des/Silkscreen Top")
		(7 "B.SilkS" user "Ref Des/Silkscreen Bottom")
		(1 "F.Mask" user "Board Geometry/Soldermask Top")
		(3 "B.Mask" user "Board Geometry/Soldermask Bottom")
		(17 "Dwgs.User" user "User.Drawings")
		(19 "Cmts.User" user "User.Comments")
		(21 "Eco1.User" user "User.Eco1")
		(23 "Eco2.User" user "User.Eco2")
		(25 "Edge.Cuts" user "Board Geometry/Outline")
		(27 "Margin" user)
		(31 "F.CrtYd" user "Package Geometry/Place Bound Top")
		(29 "B.CrtYd" user "Package Geometry/Place Bound Bottom")
		(35 "F.Fab" user "Ref Des/Assembly Top")
		(33 "B.Fab" user "Ref Des/Assembly Bottom")
	)
	(footprint ""
		(layer "F.Cu")
		(at 407.40076 -57.79389)
		(property "Reference" "C8E7"
			(at 0 0 0)
			(layer "F.SilkS")
			(hide yes)
			(effects
				(font
					(size 1.27 1.27)
				)
			)
		)
		(property "Value" "*"
			(at -0.0762 -6.2357 0)
			(unlocked yes)
			(layer "F.Fab")
			(hide yes)
			(effects
				(font
					(size 1.27 1.016)
					(thickness 0.1524)
				)
			)
		)
		(property "Device Type" "SC22U16V5MX-4-GP_SMD-BCG5-SC22A"
			(at -0.0762 -8.2677 0)
			(unlocked yes)
			(layer "F.Fab")
			(hide yes)
			(effects
				(font
					(size 1.27 1.016)
					(thickness 0.1524)
				)
			)
		)
		(duplicate_pad_numbers_are_jumpers no)
		(fp_line
			(start 0.635 0)
			(end -0.635 0)
			(stroke
				(width 0.508)
				(type default)
			)
			(layer "F.SilkS")
		)
		(fp_rect
			(start -0.9652 1.778)
			(end 0.9652 -1.778)
			(stroke
				(width 0)
				(type default)
			)
			(fill no)
			(layer "F.CrtYd")
		)
		(fp_poly
			(pts
				(xy -0.9652 -1.778) (xy 0.9652 -1.778) (xy 0.9652 1.778) (xy -0.9652 1.778)
			)
			(stroke
				(width 0)
				(type default)
			)
			(fill no)
			(layer "F.Fab")
		)
		(pad "1" smd rect
			(at 0 -0.9652)
			(size 1.397 1.143)
			(layers "F.Cu" "F.Mask" "F.Paste")
			(net "P5V_STBY")
		)
		(pad "2" smd rect
			(at 0 0.9652)
			(size 1.397 1.143)
			(layers "F.Cu" "F.Mask" "F.Paste")
			(net "GND")
		)
	)
	(footprint ""
		(layer "F.Cu")
		(at 406.0825 -50.038 90)
		(property "Reference" "R8D27"
			(at 0 0 90)
			(layer "F.SilkS")
			(hide yes)
			(effects
				(font
					(size 1.27 1.27)
				)
			)
		)
		(property "Value" ""
			(at 0 0 90)
			(layer "F.Fab")
			(effects
				(font
					(size 1.27 1.27)
				)
			)
		)
		(duplicate_pad_numbers_are_jumpers no)
		(fp_poly
			(pts
				(xy -0.2794 -0.1016) (xy 0.2794 -0.1016) (xy 0.2794 0.9906) (xy -0.2794 0.9906)
			)
			(stroke
				(width 0)
				(type default)
			)
			(fill no)
			(layer "F.CrtYd")
		)
		(fp_line
			(start 0.2794 -0.1016)
			(end -0.2794 -0.1016)
			(stroke
				(width 0.1)
				(type default)
			)
			(layer "F.Fab")
		)
		(fp_line
			(start -0.2794 -0.1016)
			(end -0.2794 0.9906)
			(stroke
				(width 0.1)
				(type default)
			)
			(layer "F.Fab")
		)
		(fp_line
			(start 0.2794 0.9906)
			(end 0.2794 -0.1016)
			(stroke
				(width 0.1)
				(type default)
			)
			(layer "F.Fab")
		)
		(fp_line
			(start -0.2794 0.9906)
			(end 0.2794 0.9906)
			(stroke
				(width 0.1)
				(type default)
			)
			(layer "F.Fab")
		)
		(pad "1" smd rect
			(at 0 0 90)
			(size 0.508 0.508)
			(layers "F.Cu" "F.Mask" "F.Paste")
			(net "PD_FRU_WP")
		)
		(pad "2" smd rect
			(at 0 0.889 90)
			(size 0.508 0.508)
			(layers "F.Cu" "F.Mask" "F.Paste")
			(net "GND")
		)
		(zone
			(layer "F.Cu")
			(hatch none 0.5)
			(connect_pads
				(clearance 0)
			)
			(min_thickness 0.25)
			(keepout
				(tracks allowed)
				(vias not_allowed)
				(pads allowed)
				(copperpour not_allowed)
				(footprints allowed)
			)
			(placement
				(enabled no)
				(sheetname "")
			)
			(fill
				(thermal_gap 0.5)
				(thermal_bridge_width 0.5)
				(island_removal_mode 0)
			)
			(polygon
				(pts
					(xy 406.3365 -49.784) (xy 406.3365 -50.292) (xy 406.7175 -50.292) (xy 406.7175 -49.784)
				)
			)
		)
		(zone
			(layer "F.Cu")
			(hatch none 0.5)
			(connect_pads
				(clearance 0)
			)
			(min_thickness 0.25)
			(keepout
				(tracks not_allowed)
				(vias allowed)
				(pads allowed)
				(copperpour not_allowed)
				(footprints allowed)
			)
			(placement
				(enabled no)
				(sheetname "")
			)
			(fill
				(thermal_gap 0.5)
				(thermal_bridge_width 0.5)
				(island_removal_mode 0)
			)
			(polygon
				(pts
					(xy 406.7175 -49.784) (xy 406.7175 -50.292) (xy 406.3365 -50.292) (xy 406.3365 -49.784)
				)
			)
		)
	)
	(footprint ""
		(layer "F.Cu")
		(at -2.5146 -126.8222 -90)
		(property "Reference" "R1B11"
			(at 0 0 270)
			(layer "F.SilkS")
			(hide yes)
			(effects
				(font
					(size 1.27 1.27)
				)
			)
		)
		(property "Value" ""
			(at 0 0 270)
			(layer "F.Fab")
			(effects
				(font
					(size 1.27 1.27)
				)
			)
		)
		(duplicate_pad_numbers_are_jumpers no)
		(fp_rect
			(start 0.2794 0.9906)
			(end -0.2794 -0.1016)
			(stroke
				(width 0)
				(type default)
			)
			(fill no)
			(layer "F.CrtYd")
		)
		(fp_line
			(start -0.2794 0.9906)
			(end 0.2794 0.9906)
			(stroke
				(width 0.1)
				(type default)
			)
			(layer "F.Fab")
		)
		(fp_line
			(start 0.2794 0.9906)
			(end 0.2794 -0.1016)
			(stroke
				(width 0.1)
				(type default)
			)
			(layer "F.Fab")
		)
		(fp_line
			(start -0.2794 -0.1016)
			(end -0.2794 0.9906)
			(stroke
				(width 0.1)
				(type default)
			)
			(layer "F.Fab")
		)
		(fp_line
			(start 0.2794 -0.1016)
			(end -0.2794 -0.1016)
			(stroke
				(width 0.1)
				(type default)
			)
			(layer "F.Fab")
		)
		(pad "1" smd rect
			(at 0 0 270)
			(size 0.508 0.508)
			(layers "F.Cu" "F.Mask" "F.Paste")
			(net "SVID_ALERT_PVDDQ_KLM")
		)
		(pad "2" smd rect
			(at 0 0.889 270)
			(size 0.508 0.508)
			(layers "F.Cu" "F.Mask" "F.Paste")
			(net "SVID_ALERT1_CPU1_R_N")
		)
		(zone
			(layer "F.Cu")
			(hatch none 0.5)
			(connect_pads
				(clearance 0)
			)
			(min_thickness 0.25)
			(keepout
				(tracks not_allowed)
				(vias allowed)
				(pads allowed)
				(copperpour not_allowed)
				(footprints allowed)
			)
			(placement
				(enabled no)
				(sheetname "")
			)
			(fill
				(thermal_gap 0.5)
				(thermal_bridge_width 0.5)
				(island_removal_mode 0)
			)
			(polygon
				(pts
					(xy -3.1496 -126.5682) (xy -2.7686 -126.5682) (xy -2.7686 -127.0762) (xy -3.1496 -127.0762)
				)
			)
		)
		(zone
			(layer "F.Cu")
			(hatch none 0.5)
			(connect_pads
				(clearance 0)
			)
			(min_thickness 0.25)
			(keepout
				(tracks allowed)
				(vias not_allowed)
				(pads allowed)
				(copperpour not_allowed)
				(footprints allowed)
			)
			(placement
				(enabled no)
				(sheetname "")
			)
			(fill
				(thermal_gap 0.5)
				(thermal_bridge_width 0.5)
				(island_removal_mode 0)
			)
			(polygon
				(pts
					(xy -3.1496 -126.5682) (xy -2.7686 -126.5682) (xy -2.7686 -127.0762) (xy -3.1496 -127.0762)
				)
			)
		)
	)
)
